(kicad_pcb
	(version 20260206)
	(generator "pcbnew")
	(generator_version "10.0")
	(general
		(thickness 1.6)
		(legacy_teardrops no)
	)
	(paper "A4")
	(title_block
		(title "Bryce Canyon_R.DPB_16317-1_OCP.brd")
		(comment 1 "Bryce Canyon / footprints 73-79 of 2099")
	)
	(layers
		(0 "F.Cu" signal "TOP")
		(4 "In1.Cu" signal "L2GND")
		(6 "In2.Cu" signal "L3")
		(8 "In3.Cu" signal "L4VCC")
		(10 "In4.Cu" signal "L5VCC")
		(12 "In5.Cu" signal "L6")
		(14 "In6.Cu" signal "L7GND")
		(2 "B.Cu" signal "BOTTOM")
		(9 "F.Adhes" user "F.Adhesive")
		(11 "B.Adhes" user "B.Adhesive")
		(13 "F.Paste" user "Package Geometry/Pastemask Top")
		(15 "B.Paste" user "Package Geometry/Pastemask Bottom")
		(5 "F.SilkS" user "Ref Des/Silkscreen Top")
		(7 "B.SilkS" user "Ref Des/Silkscreen Bottom")
		(1 "F.Mask" user "Board Geometry/Soldermask Top")
		(3 "B.Mask" user "Board Geometry/Soldermask Bottom")
		(17 "Dwgs.User" user "User.Drawings")
		(19 "Cmts.User" user "User.Comments")
		(21 "Eco1.User" user "User.Eco1")
		(23 "Eco2.User" user "User.Eco2")
		(25 "Edge.Cuts" user "Board Geometry/Outline")
		(27 "Margin" user)
		(31 "F.CrtYd" user "Package Geometry/Place Bound Top")
		(29 "B.CrtYd" user "Package Geometry/Place Bound Bottom")
		(35 "F.Fab" user "Ref Des/Assembly Top")
		(33 "B.Fab" user "Ref Des/Assembly Bottom")
	)
	(footprint ""
		(layer "F.Cu")
		(at 77.978 -260.858)
		(property "Reference" "Q8"
			(at 0 0 0)
			(layer "F.SilkS")
			(hide yes)
			(effects
				(font
					(size 1.27 1.27)
				)
			)
		)
		(property "Value" "AO4407AL-GP"
			(at -3.707384 -1.5367 0)
			(unlocked yes)
			(layer "F.Fab")
			(hide yes)
			(effects
				(font
					(size 1.016 1.016)
					(thickness 0.1524)
				)
			)
		)
		(property "Device Type" "SOIC8H69"
			(at -3.707384 -3.0607 0)
			(unlocked yes)
			(layer "F.Fab")
			(hide yes)
			(effects
				(font
					(size 1.016 1.016)
					(thickness 0.1524)
				)
			)
		)
		(duplicate_pad_numbers_are_jumpers no)
		(fp_line
			(start -2.7432 -1.4224)
			(end -2.7432 1.4224)
			(stroke
				(width 0.1524)
				(type default)
			)
			(layer "F.SilkS")
		)
		(fp_line
			(start -2.7432 1.4224)
			(end -2.6416 1.4224)
			(stroke
				(width 0.1524)
				(type default)
			)
			(layer "F.SilkS")
		)
		(fp_line
			(start -2.7432 1.4224)
			(end 2.1336 1.4224)
			(stroke
				(width 0.1524)
				(type default)
			)
			(layer "F.SilkS")
		)
		(fp_line
			(start -2.7178 -0.508)
			(end -2.1844 -0.0508)
			(stroke
				(width 0.1524)
				(type default)
			)
			(layer "F.SilkS")
		)
		(fp_line
			(start -2.6289 3.4417)
			(end -2.6289 1.4732)
			(stroke
				(width 0.381)
				(type default)
			)
			(layer "F.SilkS")
		)
		(fp_line
			(start -2.1844 -0.0508)
			(end -2.7178 0.508)
			(stroke
				(width 0.1524)
				(type default)
			)
			(layer "F.SilkS")
		)
		(fp_line
			(start 2.1336 -1.4224)
			(end -2.7432 -1.4224)
			(stroke
				(width 0.1524)
				(type default)
			)
			(layer "F.SilkS")
		)
		(fp_line
			(start 2.1336 1.4224)
			(end 2.1336 -1.4224)
			(stroke
				(width 0.1524)
				(type default)
			)
			(layer "F.SilkS")
		)
		(fp_poly
			(pts
				(xy -2.2098 -1.4224) (xy -2.2098 1.4224) (xy 2.2098 1.4224) (xy 2.2098 -1.4224)
			)
			(stroke
				(width 0)
				(type default)
			)
			(fill yes)
			(layer "F.SilkS")
		)
		(fp_rect
			(start -2.450084 2.999994)
			(end 2.450084 -2.999994)
			(stroke
				(width 0)
				(type default)
			)
			(fill no)
			(layer "F.CrtYd")
		)
		(fp_poly
			(pts
				(xy -2.8194 3.6322) (xy -2.8194 -3.6322) (xy 2.8194 -3.6322) (xy 2.8194 1.18364) (xy 2.450084 1.18364)
				(xy 2.450084 -2.999994) (xy -2.450084 -2.999994) (xy -2.450084 2.999994) (xy 2.450084 2.999994)
				(xy 2.450084 1.18618) (xy 2.8194 1.18618) (xy 2.8194 3.6322)
			)
			(stroke
				(width 0)
				(type default)
			)
			(fill no)
			(layer "F.CrtYd")
		)
		(fp_rect
			(start -2.8194 3.6322)
			(end 2.8194 -3.6322)
			(stroke
				(width 0)
				(type default)
			)
			(fill no)
			(layer "F.Fab")
		)
		(pad "1" smd rect
			(at -1.905 2.54)
			(size 0.635 1.651)
			(layers "F.Cu" "F.Mask" "F.Paste")
			(net "P12V_B")
		)
		(pad "2" smd rect
			(at -0.635 2.54)
			(size 0.635 1.651)
			(layers "F.Cu" "F.Mask" "F.Paste")
			(net "P12V_B")
		)
		(pad "3" smd rect
			(at 0.635 2.54)
			(size 0.635 1.651)
			(layers "F.Cu" "F.Mask" "F.Paste")
			(net "P12V_B")
		)
		(pad "4" smd rect
			(at 1.905 2.54)
			(size 0.635 1.651)
			(layers "F.Cu" "F.Mask" "F.Paste")
			(net "SW_HDD_N2")
		)
		(pad "5" smd rect
			(at 1.905 -2.54)
			(size 0.635 1.651)
			(layers "F.Cu" "F.Mask" "F.Paste")
			(net "P12V_HDD2")
		)
		(pad "6" smd rect
			(at 0.635 -2.54)
			(size 0.635 1.651)
			(layers "F.Cu" "F.Mask" "F.Paste")
			(net "P12V_HDD2")
		)
		(pad "7" smd rect
			(at -0.635 -2.54)
			(size 0.635 1.651)
			(layers "F.Cu" "F.Mask" "F.Paste")
			(net "P12V_HDD2")
		)
		(pad "8" smd rect
			(at -1.905 -2.54)
			(size 0.635 1.651)
			(layers "F.Cu" "F.Mask" "F.Paste")
			(net "P12V_HDD2")
		)
	)
	(footprint ""
		(layer "F.Cu")
		(at 394.716 -249.5804 90)
		(property "Reference" "R291"
			(at 0 0 90)
			(layer "F.SilkS")
			(hide yes)
			(effects
				(font
					(size 1.27 1.27)
				)
			)
		)
		(property "Value" "4K7R2J-2-GP"
			(at 0.064008 -3.993896 90)
			(unlocked yes)
			(layer "F.Fab")
			(hide yes)
			(effects
				(font
					(size 1.016 1.016)
					(thickness 0.1524)
				)
			)
		)
		(property "Device Type" "R402H16"
			(at 0.064008 -5.517896 90)
			(unlocked yes)
			(layer "F.Fab")
			(hide yes)
			(effects
				(font
					(size 1.016 1.016)
					(thickness 0.1524)
				)
			)
		)
		(duplicate_pad_numbers_are_jumpers no)
		(fp_line
			(start 0.508 -0.9398)
			(end -0.508 -0.9398)
			(stroke
				(width 0.1524)
				(type default)
			)
			(layer "F.SilkS")
		)
		(fp_line
			(start -0.508 -0.9398)
			(end -0.508 0.9398)
			(stroke
				(width 0.1524)
				(type default)
			)
			(layer "F.SilkS")
		)
		(fp_rect
			(start -0.508 0.9398)
			(end 0.508 -0.9398)
			(stroke
				(width 0)
				(type default)
			)
			(fill no)
			(layer "F.CrtYd")
		)
		(fp_rect
			(start -0.508 0.9398)
			(end 0.508 -0.9398)
			(stroke
				(width 0)
				(type default)
			)
			(fill no)
			(layer "F.Fab")
		)
		(pad "1" smd custom
			(at 0 -0.4445 90)
			(size 0.1397 0.1397)
			(layers "F.Cu" "F.Mask" "F.Paste")
			(net "P12V_B")
			(options
				(clearance outline)
				(anchor circle)
			)
			(primitives
				(gr_poly
					(pts
						(arc
							(start -0.1778 -0.2794)
							(mid -0.249642 -0.249642)
							(end -0.2794 -0.1778)
						)
						(arc
							(start -0.2794 0.1778)
							(mid -0.249642 0.249642)
							(end -0.1778 0.2794)
						)
						(arc
							(start 0.1778 0.2794)
							(mid 0.249642 0.249642)
							(end 0.2794 0.1778)
						)
						(arc
							(start 0.2794 -0.1778)
							(mid 0.249642 -0.249642)
							(end 0.1778 -0.2794)
						)
					)
					(width 0)
					(fill yes)
				)
			)
		)
		(pad "2" smd custom
			(at 0 0.4445 90)
			(size 0.1397 0.1397)
			(layers "F.Cu" "F.Mask" "F.Paste")
			(net "SW_HDD_P8")
			(options
				(clearance outline)
				(anchor circle)
			)
			(primitives
				(gr_poly
					(pts
						(arc
							(start -0.1778 -0.2794)
							(mid -0.249642 -0.249642)
							(end -0.2794 -0.1778)
						)
						(arc
							(start -0.2794 0.1778)
							(mid -0.249642 0.249642)
							(end -0.1778 0.2794)
						)
						(arc
							(start 0.1778 0.2794)
							(mid 0.249642 0.249642)
							(end 0.2794 0.1778)
						)
						(arc
							(start 0.2794 -0.1778)
							(mid 0.249642 -0.249642)
							(end 0.1778 -0.2794)
						)
					)
					(width 0)
					(fill yes)
				)
			)
		)
	)
	(footprint ""
		(layer "F.Cu")
		(at 473.8878 -9.6774 -90)
		(property "Reference" "R890"
			(at 0 0 270)
			(layer "F.SilkS")
			(hide yes)
			(effects
				(font
					(size 1.27 1.27)
				)
			)
		)
		(property "Value" "300KR2F-GP"
			(at 0.064008 -3.993896 270)
			(unlocked yes)
			(layer "F.Fab")
			(hide yes)
			(effects
				(font
					(size 1.016 1.016)
					(thickness 0.1524)
				)
			)
		)
		(property "Device Type" "R402H16"
			(at 0.064008 -5.517896 270)
			(unlocked yes)
			(layer "F.Fab")
			(hide yes)
			(effects
				(font
					(size 1.016 1.016)
					(thickness 0.1524)
				)
			)
		)
		(duplicate_pad_numbers_are_jumpers no)
		(fp_line
			(start -0.508 -0.9398)
			(end -0.508 0.9398)
			(stroke
				(width 0.1524)
				(type default)
			)
			(layer "F.SilkS")
		)
		(fp_line
			(start 0.508 -0.9398)
			(end -0.508 -0.9398)
			(stroke
				(width 0.1524)
				(type default)
			)
			(layer "F.SilkS")
		)
		(fp_rect
			(start -0.508 0.9398)
			(end 0.508 -0.9398)
			(stroke
				(width 0)
				(type default)
			)
			(fill no)
			(layer "F.CrtYd")
		)
		(fp_rect
			(start -0.508 0.9398)
			(end 0.508 -0.9398)
			(stroke
				(width 0)
				(type default)
			)
			(fill no)
			(layer "F.Fab")
		)
		(pad "1" smd custom
			(at 0 -0.4445 270)
			(size 0.1397 0.1397)
			(layers "F.Cu" "F.Mask" "F.Paste")
			(net "SW_HDD_N35")
			(options
				(clearance outline)
				(anchor circle)
			)
			(primitives
				(gr_poly
					(pts
						(arc
							(start -0.1778 -0.2794)
							(mid -0.249642 -0.249642)
							(end -0.2794 -0.1778)
						)
						(arc
							(start -0.2794 0.1778)
							(mid -0.249642 0.249642)
							(end -0.1778 0.2794)
						)
						(arc
							(start 0.1778 0.2794)
							(mid 0.249642 0.249642)
							(end 0.2794 0.1778)
						)
						(arc
							(start 0.2794 -0.1778)
							(mid 0.249642 -0.249642)
							(end 0.1778 -0.2794)
						)
					)
					(width 0)
					(fill yes)
				)
			)
		)
		(pad "2" smd custom
			(at 0 0.4445 270)
			(size 0.1397 0.1397)
			(layers "F.Cu" "F.Mask" "F.Paste")
			(net "P12V_B")
			(options
				(clearance outline)
				(anchor circle)
			)
			(primitives
				(gr_poly
					(pts
						(arc
							(start -0.1778 -0.2794)
							(mid -0.249642 -0.249642)
							(end -0.2794 -0.1778)
						)
						(arc
							(start -0.2794 0.1778)
							(mid -0.249642 0.249642)
							(end -0.1778 0.2794)
						)
						(arc
							(start 0.1778 0.2794)
							(mid 0.249642 0.249642)
							(end 0.2794 0.1778)
						)
						(arc
							(start 0.2794 -0.1778)
							(mid 0.249642 -0.249642)
							(end 0.1778 -0.2794)
						)
					)
					(width 0)
					(fill yes)
				)
			)
		)
	)
	(footprint ""
		(layer "F.Cu")
		(at 243.519452 -359.617772 180)
		(property "Reference" "C564"
			(at 0 0 180)
			(layer "F.SilkS")
			(hide yes)
			(effects
				(font
					(size 1.27 1.27)
				)
			)
		)
		(property "Value" "SC1U16V3KX-5GP"
			(at 0 -2.8194 180)
			(unlocked yes)
			(layer "F.Fab")
			(hide yes)
			(effects
				(font
					(size 1.016 1.016)
					(thickness 0.1524)
				)
			)
		)
		(property "Device Type" "C603H36"
			(at 0 -4.3434 180)
			(unlocked yes)
			(layer "F.Fab")
			(hide yes)
			(effects
				(font
					(size 1.016 1.016)
					(thickness 0.1524)
				)
			)
		)
		(duplicate_pad_numbers_are_jumpers no)
		(fp_line
			(start 0.508 0)
			(end -0.508 0)
			(stroke
				(width 0.2032)
				(type default)
			)
			(layer "F.SilkS")
		)
		(fp_rect
			(start -0.5842 1.3335)
			(end 0.5842 -1.3335)
			(stroke
				(width 0)
				(type default)
			)
			(fill no)
			(layer "F.CrtYd")
		)
		(fp_rect
			(start -0.5842 1.3335)
			(end 0.5842 -1.3335)
			(stroke
				(width 0)
				(type default)
			)
			(fill no)
			(layer "F.Fab")
		)
		(pad "1" smd custom
			(at 0 -0.762 180)
			(size 0.2159 0.2159)
			(layers "F.Cu" "F.Mask" "F.Paste")
			(net "MB3_CM_OV_R")
			(options
				(clearance outline)
				(anchor circle)
			)
			(primitives
				(gr_poly
					(pts
						(arc
							(start -0.3302 -0.4318)
							(mid -0.402042 -0.402042)
							(end -0.4318 -0.3302)
						)
						(arc
							(start -0.4318 0.3302)
							(mid -0.402042 0.402042)
							(end -0.3302 0.4318)
						)
						(arc
							(start 0.3302 0.4318)
							(mid 0.402042 0.402042)
							(end 0.4318 0.3302)
						)
						(arc
							(start 0.4318 -0.3302)
							(mid 0.402042 -0.402042)
							(end 0.3302 -0.4318)
						)
					)
					(width 0)
					(fill yes)
				)
			)
		)
		(pad "2" smd custom
			(at 0 0.762 180)
			(size 0.2159 0.2159)
			(layers "F.Cu" "F.Mask" "F.Paste")
			(net "AGND_CURRENT_DPB")
			(options
				(clearance outline)
				(anchor circle)
			)
			(primitives
				(gr_poly
					(pts
						(arc
							(start -0.3302 -0.4318)
							(mid -0.402042 -0.402042)
							(end -0.4318 -0.3302)
						)
						(arc
							(start -0.4318 0.3302)
							(mid -0.402042 0.402042)
							(end -0.3302 0.4318)
						)
						(arc
							(start 0.3302 0.4318)
							(mid 0.402042 0.402042)
							(end 0.4318 0.3302)
						)
						(arc
							(start 0.4318 -0.3302)
							(mid 0.402042 -0.402042)
							(end 0.3302 -0.4318)
						)
					)
					(width 0)
					(fill yes)
				)
			)
		)
	)
	(footprint ""
		(layer "F.Cu")
		(at 98.806 -32.8676 180)
		(property "Reference" "R672"
			(at 0 0 180)
			(layer "F.SilkS")
			(hide yes)
			(effects
				(font
					(size 1.27 1.27)
				)
			)
		)
		(property "Value" "220R3F-1-GP"
			(at -0.0254 -2.5146 180)
			(unlocked yes)
			(layer "F.Fab")
			(hide yes)
			(effects
				(font
					(size 1.016 1.016)
					(thickness 0.1524)
				)
			)
		)
		(property "Device Type" "R603H22"
			(at -0.0254 -4.0386 180)
			(unlocked yes)
			(layer "F.Fab")
			(hide yes)
			(effects
				(font
					(size 1.016 1.016)
					(thickness 0.1524)
				)
			)
		)
		(duplicate_pad_numbers_are_jumpers no)
		(fp_line
			(start 0.2032 0)
			(end 0.4826 0)
			(stroke
				(width 0.2032)
				(type default)
			)
			(layer "F.SilkS")
		)
		(fp_line
			(start -0.4826 0)
			(end -0.2032 0)
			(stroke
				(width 0.2032)
				(type default)
			)
			(layer "F.SilkS")
		)
		(fp_rect
			(start -0.5842 1.3335)
			(end 0.5842 -1.3335)
			(stroke
				(width 0)
				(type default)
			)
			(fill no)
			(layer "F.CrtYd")
		)
		(fp_rect
			(start -0.5842 1.3335)
			(end 0.5842 -1.3335)
			(stroke
				(width 0)
				(type default)
			)
			(fill no)
			(layer "F.Fab")
		)
		(pad "1" smd custom
			(at 0 -0.762 180)
			(size 0.2159 0.2159)
			(layers "F.Cu" "F.Mask" "F.Paste")
			(net "HDD_PRSNT_26")
			(options
				(clearance outline)
				(anchor circle)
			)
			(primitives
				(gr_poly
					(pts
						(arc
							(start -0.3302 -0.4318)
							(mid -0.402042 -0.402042)
							(end -0.4318 -0.3302)
						)
						(arc
							(start -0.4318 0.3302)
							(mid -0.402042 0.402042)
							(end -0.3302 0.4318)
						)
						(arc
							(start 0.3302 0.4318)
							(mid 0.402042 0.402042)
							(end 0.4318 0.3302)
						)
						(arc
							(start 0.4318 -0.3302)
							(mid 0.402042 -0.402042)
							(end 0.3302 -0.4318)
						)
					)
					(width 0)
					(fill yes)
				)
			)
		)
		(pad "2" smd custom
			(at 0 0.762 180)
			(size 0.2159 0.2159)
			(layers "F.Cu" "F.Mask" "F.Paste")
			(net "DRIVE_B_26_INS")
			(options
				(clearance outline)
				(anchor circle)
			)
			(primitives
				(gr_poly
					(pts
						(arc
							(start -0.3302 -0.4318)
							(mid -0.402042 -0.402042)
							(end -0.4318 -0.3302)
						)
						(arc
							(start -0.4318 0.3302)
							(mid -0.402042 0.402042)
							(end -0.3302 0.4318)
						)
						(arc
							(start 0.3302 0.4318)
							(mid 0.402042 0.402042)
							(end 0.4318 0.3302)
						)
						(arc
							(start 0.4318 -0.3302)
							(mid 0.402042 -0.402042)
							(end 0.3302 -0.4318)
						)
					)
					(width 0)
					(fill yes)
				)
			)
		)
	)
	(footprint ""
		(layer "F.Cu")
		(at 233.26852 -233.023156 180)
		(property "Reference" "R69"
			(at 0 0 180)
			(layer "F.SilkS")
			(hide yes)
			(effects
				(font
					(size 1.27 1.27)
				)
			)
		)
		(property "Value" "4K7R2F-GP"
			(at 0.064008 -3.993896 180)
			(unlocked yes)
			(layer "F.Fab")
			(hide yes)
			(effects
				(font
					(size 1.016 1.016)
					(thickness 0.1524)
				)
			)
		)
		(property "Device Type" "R402H16"
			(at 0.064008 -5.517896 180)
			(unlocked yes)
			(layer "F.Fab")
			(hide yes)
			(effects
				(font
					(size 1.016 1.016)
					(thickness 0.1524)
				)
			)
		)
		(duplicate_pad_numbers_are_jumpers no)
		(fp_line
			(start 0.508 -0.9398)
			(end -0.508 -0.9398)
			(stroke
				(width 0.1524)
				(type default)
			)
			(layer "F.SilkS")
		)
		(fp_line
			(start -0.508 -0.9398)
			(end -0.508 0.9398)
			(stroke
				(width 0.1524)
				(type default)
			)
			(layer "F.SilkS")
		)
		(fp_rect
			(start -0.508 0.9398)
			(end 0.508 -0.9398)
			(stroke
				(width 0)
				(type default)
			)
			(fill no)
			(layer "F.CrtYd")
		)
		(fp_rect
			(start -0.508 0.9398)
			(end 0.508 -0.9398)
			(stroke
				(width 0)
				(type default)
			)
			(fill no)
			(layer "F.Fab")
		)
		(pad "1" smd custom
			(at 0 -0.4445 180)
			(size 0.1397 0.1397)
			(layers "F.Cu" "F.Mask" "F.Paste")
			(net "IO_EXP1_A1")
			(options
				(clearance outline)
				(anchor circle)
			)
			(primitives
				(gr_poly
					(pts
						(arc
							(start -0.1778 -0.2794)
							(mid -0.249642 -0.249642)
							(end -0.2794 -0.1778)
						)
						(arc
							(start -0.2794 0.1778)
							(mid -0.249642 0.249642)
							(end -0.1778 0.2794)
						)
						(arc
							(start 0.1778 0.2794)
							(mid 0.249642 0.249642)
							(end 0.2794 0.1778)
						)
						(arc
							(start 0.2794 -0.1778)
							(mid 0.249642 -0.249642)
							(end 0.1778 -0.2794)
						)
					)
					(width 0)
					(fill yes)
				)
			)
		)
		(pad "2" smd custom
			(at 0 0.4445 180)
			(size 0.1397 0.1397)
			(layers "F.Cu" "F.Mask" "F.Paste")
			(net "GND")
			(options
				(clearance outline)
				(anchor circle)
			)
			(primitives
				(gr_poly
					(pts
						(arc
							(start -0.1778 -0.2794)
							(mid -0.249642 -0.249642)
							(end -0.2794 -0.1778)
						)
						(arc
							(start -0.2794 0.1778)
							(mid -0.249642 0.249642)
							(end -0.1778 0.2794)
						)
						(arc
							(start 0.1778 0.2794)
							(mid 0.249642 0.249642)
							(end 0.2794 0.1778)
						)
						(arc
							(start 0.2794 -0.1778)
							(mid 0.249642 -0.249642)
							(end 0.1778 -0.2794)
						)
					)
					(width 0)
					(fill yes)
				)
			)
		)
	)
	(footprint ""
		(layer "F.Cu")
		(at 382.49225 -244.874034 90)
		(property "Reference" "VIA17"
			(at 0 0 90)
			(layer "F.SilkS")
			(hide yes)
			(effects
				(font
					(size 1.27 1.27)
				)
			)
		)
		(property "Value" "100OHM-8L-2D36MM-L18-GP"
			(at 3.8989 0.5715 90)
			(unlocked yes)
			(layer "F.Fab")
			(hide yes)
			(effects
				(font
					(size 1.016 1.016)
					(thickness 0.1524)
				)
			)
		)
		(property "Device Type" "VIA-PCIE-4P-414097"
			(at 3.8989 -0.9525 90)
			(unlocked yes)
			(layer "F.Fab")
			(hide yes)
			(effects
				(font
					(size 1.016 1.016)
					(thickness 0.1524)
				)
			)
		)
		(duplicate_pad_numbers_are_jumpers no)
		(fp_rect
			(start -2.0701 0.4826)
			(end 2.0701 -0.4826)
			(stroke
				(width 0)
				(type default)
			)
			(fill no)
			(layer "F.CrtYd")
		)
		(fp_rect
			(start -2.0701 0.4826)
			(end 2.0701 -0.4826)
			(stroke
				(width 0)
				(type default)
			)
			(fill no)
			(layer "F.Fab")
		)
		(pad "1" thru_hole circle
			(at -1.5875 0 90)
			(size 0.508 0.508)
			(drill 0.254)
			(layers "*.Cu" "*.Mask")
			(remove_unused_layers no)
			(net "GND")
			(clearance 0.2286)
			(thermal_gap 0.2286)
		)
		(pad "2" thru_hole circle
			(at -0.5715 0 90)
			(size 0.508 0.508)
			(drill 0.254)
			(layers "*.Cu" "*.Mask")
			(remove_unused_layers no)
			(net "PHY_SCC_B_TO_DRV_B_8_DP")
			(clearance 0.2286)
			(thermal_gap 0.2286)
		)
		(pad "3" thru_hole circle
			(at 0.5715 0 90)
			(size 0.508 0.508)
			(drill 0.254)
			(layers "*.Cu" "*.Mask")
			(remove_unused_layers no)
			(net "PHY_SCC_B_TO_DRV_B_8_DN")
			(clearance 0.2286)
			(thermal_gap 0.2286)
		)
		(pad "4" thru_hole circle
			(at 1.5875 0 90)
			(size 0.508 0.508)
			(drill 0.254)
			(layers "*.Cu" "*.Mask")
			(remove_unused_layers no)
			(net "GND")
			(clearance 0.2286)
			(thermal_gap 0.2286)
		)
	)
)
